# S9S_MB_2U (Grand Teton) — schematic netlist excerpt (pin names and nets, part order shuffled) for the footprints in the layout excerpt that follows; sources: Cadence DE-HDL packaged netlist, KiCad conversion of 03242023_DA0F0TMBIJ0_F0T_Motherboard_J_brd_V01_OCP.brd

R2493  Q_RES  1K 1% CHIP  pkg 0402LF  page 115 : A = PWRGD_FAIL_CPU0_GH ; B = PWRGD_FAIL_CPU0_GH_R1
C622  Q_CAP  1UF 25V 10% EMPTY  pkg C0402  page 129 : A = RST_PLD_CPU0_DRAM_AB_N ; B = GND

(kicad_pcb
	(version 20260206)
	(generator "pcbnew")
	(generator_version "10.0")
	(general
		(thickness 1.6)
		(legacy_teardrops no)
	)
	(paper "A4")
	(title_block
		(title "03242023_DA0F0TMBIJ0_F0T_Motherboard_J_brd_V01_OCP.brd")
		(comment 1 "Grand Teton / footprints 4545-4546 of 6105")
	)
	(layers
		(0 "F.Cu" signal "TOP")
		(4 "In1.Cu" signal "GND")
		(6 "In2.Cu" signal "IN1")
		(8 "In3.Cu" signal "GND1")
		(10 "In4.Cu" signal "IN2")
		(12 "In5.Cu" signal "GND2")
		(14 "In6.Cu" signal "IN3")
		(16 "In7.Cu" signal "GND3")
		(18 "In8.Cu" signal "VCC")
		(20 "In9.Cu" signal "VCC1")
		(22 "In10.Cu" signal "GND4")
		(24 "In11.Cu" signal "IN4")
		(26 "In12.Cu" signal "GND5")
		(28 "In13.Cu" signal "IN5")
		(30 "In14.Cu" signal "GND6")
		(32 "In15.Cu" signal "IN6")
		(34 "In16.Cu" signal "GND7")
		(2 "B.Cu" signal "BOTTOM")
		(9 "F.Adhes" user "F.Adhesive")
		(11 "B.Adhes" user "B.Adhesive")
		(13 "F.Paste" user "Package Geometry/Pastemask Top")
		(15 "B.Paste" user "Package Geometry/Pastemask Bottom")
		(5 "F.SilkS" user "Ref Des/Silkscreen Top")
		(7 "B.SilkS" user "Ref Des/Silkscreen Bottom")
		(1 "F.Mask" user "Board Geometry/Soldermask Top")
		(3 "B.Mask" user "Board Geometry/Soldermask Bottom")
		(17 "Dwgs.User" user "User.Drawings")
		(19 "Cmts.User" user "User.Comments")
		(21 "Eco1.User" user "User.Eco1")
		(23 "Eco2.User" user "User.Eco2")
		(25 "Edge.Cuts" user "Board Geometry/Outline")
		(27 "Margin" user)
		(31 "F.CrtYd" user "Package Geometry/Place Bound Top")
		(29 "B.CrtYd" user "Package Geometry/Place Bound Bottom")
		(35 "F.Fab" user "Ref Des/Assembly Top")
		(33 "B.Fab" user "Ref Des/Assembly Bottom")
	)
	(footprint ""
		(layer "B.Cu")
		(at 456.003406 -318.266826 180)
		(property "Reference" "R2493"
			(at 0 0 0)
			(layer "B.SilkS")
			(hide yes)
			(effects
				(font
					(size 1.27 1.27)
				)
				(justify mirror)
			)
		)
		(property "Value" ""
			(at 0 0 0)
			(layer "B.Fab")
			(effects
				(font
					(size 1.27 1.27)
				)
				(justify mirror)
			)
		)
		(duplicate_pad_numbers_are_jumpers no)
		(fp_line
			(start 0.7874 0.4064)
			(end 0.7874 -0.4064)
			(stroke
				(width 0.1524)
				(type default)
			)
			(layer "B.SilkS")
		)
		(fp_line
			(start 0.7874 -0.4064)
			(end -0.7874 -0.4064)
			(stroke
				(width 0.1524)
				(type default)
			)
			(layer "B.SilkS")
		)
		(fp_line
			(start -0.7874 0.4064)
			(end 0.7874 0.4064)
			(stroke
				(width 0.1524)
				(type default)
			)
			(layer "B.SilkS")
		)
		(fp_line
			(start -0.7874 -0.4064)
			(end -0.7874 0.4064)
			(stroke
				(width 0.1524)
				(type default)
			)
			(layer "B.SilkS")
		)
		(fp_line
			(start 0.67945 0.3048)
			(end 0.67945 -0.305054)
			(stroke
				(width 0.1)
				(type default)
			)
			(layer "B.Fab")
		)
		(fp_line
			(start 0.67945 -0.305054)
			(end 0.12065 -0.305054)
			(stroke
				(width 0.1)
				(type default)
			)
			(layer "B.Fab")
		)
		(fp_line
			(start 0.12065 0.3048)
			(end 0.67945 0.3048)
			(stroke
				(width 0.1)
				(type default)
			)
			(layer "B.Fab")
		)
		(fp_line
			(start 0.12065 0.2794)
			(end 0.12065 0.3048)
			(stroke
				(width 0.1)
				(type default)
			)
			(layer "B.Fab")
		)
		(fp_line
			(start 0.12065 -0.2794)
			(end -0.12065 -0.2794)
			(stroke
				(width 0.1)
				(type default)
			)
			(layer "B.Fab")
		)
		(fp_line
			(start 0.12065 -0.305054)
			(end 0.12065 -0.2794)
			(stroke
				(width 0.1)
				(type default)
			)
			(layer "B.Fab")
		)
		(fp_line
			(start -0.120396 0.3048)
			(end -0.120396 0.2794)
			(stroke
				(width 0.1)
				(type default)
			)
			(layer "B.Fab")
		)
		(fp_line
			(start -0.120396 0.2794)
			(end 0.12065 0.2794)
			(stroke
				(width 0.1)
				(type default)
			)
			(layer "B.Fab")
		)
		(fp_line
			(start -0.12065 -0.2794)
			(end -0.12065 -0.3048)
			(stroke
				(width 0.1)
				(type default)
			)
			(layer "B.Fab")
		)
		(fp_line
			(start -0.12065 -0.3048)
			(end -0.67945 -0.3048)
			(stroke
				(width 0.1)
				(type default)
			)
			(layer "B.Fab")
		)
		(fp_line
			(start -0.67945 0.3048)
			(end -0.120396 0.3048)
			(stroke
				(width 0.1)
				(type default)
			)
			(layer "B.Fab")
		)
		(fp_line
			(start -0.67945 -0.3048)
			(end -0.67945 0.3048)
			(stroke
				(width 0.1)
				(type default)
			)
			(layer "B.Fab")
		)
		(pad "1" smd circle
			(at 0.40005 0)
			(size 0 0)
			(layers "B.Cu" "B.Mask" "B.Paste")
			(net "PWRGD_FAIL_CPU0_GH")
		)
		(pad "2" smd circle
			(at -0.40005 0)
			(size 0 0)
			(layers "B.Cu" "B.Mask" "B.Paste")
			(net "PWRGD_FAIL_CPU0_GH_R1")
		)
	)
	(footprint ""
		(layer "B.Cu")
		(at 283.430726 -193.691256 -90)
		(property "Reference" "C622"
			(at 0 0 90)
			(layer "B.SilkS")
			(hide yes)
			(effects
				(font
					(size 1.27 1.27)
				)
				(justify mirror)
			)
		)
		(property "Value" ""
			(at 0 0 90)
			(layer "B.Fab")
			(effects
				(font
					(size 1.27 1.27)
				)
				(justify mirror)
			)
		)
		(duplicate_pad_numbers_are_jumpers no)
		(fp_line
			(start -0.7874 0.4064)
			(end 0.7874 0.4064)
			(stroke
				(width 0.1524)
				(type default)
			)
			(layer "B.SilkS")
		)
		(fp_line
			(start 0.7874 0.4064)
			(end 0.7874 -0.4064)
			(stroke
				(width 0.1524)
				(type default)
			)
			(layer "B.SilkS")
		)
		(fp_line
			(start -0.7874 -0.4064)
			(end -0.7874 0.4064)
			(stroke
				(width 0.1524)
				(type default)
			)
			(layer "B.SilkS")
		)
		(fp_line
			(start 0.7874 -0.4064)
			(end -0.7874 -0.4064)
			(stroke
				(width 0.1524)
				(type default)
			)
			(layer "B.SilkS")
		)
		(fp_line
			(start -0.67945 0.3048)
			(end -0.120396 0.3048)
			(stroke
				(width 0.1)
				(type default)
			)
			(layer "B.Fab")
		)
		(fp_line
			(start -0.120396 0.3048)
			(end -0.120396 0.2794)
			(stroke
				(width 0.1)
				(type default)
			)
			(layer "B.Fab")
		)
		(fp_line
			(start 0.12065 0.3048)
			(end 0.67945 0.3048)
			(stroke
				(width 0.1)
				(type default)
			)
			(layer "B.Fab")
		)
		(fp_line
			(start 0.67945 0.3048)
			(end 0.67945 -0.305054)
			(stroke
				(width 0.1)
				(type default)
			)
			(layer "B.Fab")
		)
		(fp_line
			(start -0.120396 0.2794)
			(end 0.12065 0.2794)
			(stroke
				(width 0.1)
				(type default)
			)
			(layer "B.Fab")
		)
		(fp_line
			(start 0.12065 0.2794)
			(end 0.12065 0.3048)
			(stroke
				(width 0.1)
				(type default)
			)
			(layer "B.Fab")
		)
		(fp_line
			(start -0.12065 -0.2794)
			(end -0.12065 -0.3048)
			(stroke
				(width 0.1)
				(type default)
			)
			(layer "B.Fab")
		)
		(fp_line
			(start 0.12065 -0.2794)
			(end -0.12065 -0.2794)
			(stroke
				(width 0.1)
				(type default)
			)
			(layer "B.Fab")
		)
		(fp_line
			(start -0.67945 -0.3048)
			(end -0.67945 0.3048)
			(stroke
				(width 0.1)
				(type default)
			)
			(layer "B.Fab")
		)
		(fp_line
			(start -0.12065 -0.3048)
			(end -0.67945 -0.3048)
			(stroke
				(width 0.1)
				(type default)
			)
			(layer "B.Fab")
		)
		(fp_line
			(start 0.12065 -0.305054)
			(end 0.12065 -0.2794)
			(stroke
				(width 0.1)
				(type default)
			)
			(layer "B.Fab")
		)
		(fp_line
			(start 0.67945 -0.305054)
			(end 0.12065 -0.305054)
			(stroke
				(width 0.1)
				(type default)
			)
			(layer "B.Fab")
		)
		(pad "1" smd circle
			(at 0.40005 0 90)
			(size 0 0)
			(layers "B.Cu" "B.Mask" "B.Paste")
			(net "RST_PLD_CPU0_DRAM_AB_N")
		)
		(pad "2" smd circle
			(at -0.40005 0 90)
			(size 0 0)
			(layers "B.Cu" "B.Mask" "B.Paste")
			(net "GND")
		)
	)
)
